(kicad_pcb
	(version 20260206)
	(generator "pcbnew")
	(generator_version "10.0")
	(general
		(thickness 1.6)
		(legacy_teardrops no)
	)
	(paper "A4")
	(title_block
		(title "Bryce Canyon_IOM_IOC_16318-2_OCP.brd")
		(comment 1 "Bryce Canyon / footprints 615-622 of 1605")
	)
	(layers
		(0 "F.Cu" signal "TOP")
		(4 "In1.Cu" signal "L2GND")
		(6 "In2.Cu" signal "L3")
		(8 "In3.Cu" signal "L4VCC")
		(10 "In4.Cu" signal "L5VCC")
		(12 "In5.Cu" signal "L6")
		(14 "In6.Cu" signal "L7GND")
		(2 "B.Cu" signal "BOTTOM")
		(9 "F.Adhes" user "F.Adhesive")
		(11 "B.Adhes" user "B.Adhesive")
		(13 "F.Paste" user "Package Geometry/Pastemask Top")
		(15 "B.Paste" user "Package Geometry/Pastemask Bottom")
		(5 "F.SilkS" user "Ref Des/Silkscreen Top")
		(7 "B.SilkS" user "Ref Des/Silkscreen Bottom")
		(1 "F.Mask" user "Board Geometry/Soldermask Top")
		(3 "B.Mask" user "Board Geometry/Soldermask Bottom")
		(17 "Dwgs.User" user "User.Drawings")
		(19 "Cmts.User" user "User.Comments")
		(21 "Eco1.User" user "User.Eco1")
		(23 "Eco2.User" user "User.Eco2")
		(25 "Edge.Cuts" user "Board Geometry/Outline")
		(27 "Margin" user)
		(31 "F.CrtYd" user "Package Geometry/Place Bound Top")
		(29 "B.CrtYd" user "Package Geometry/Place Bound Bottom")
		(35 "F.Fab" user "Ref Des/Assembly Top")
		(33 "B.Fab" user "Ref Des/Assembly Bottom")
	)
	(footprint ""
		(layer "F.Cu")
		(at 176.917858 -116.587524 180)
		(property "Reference" "R568"
			(at 0 0 180)
			(layer "F.SilkS")
			(hide yes)
			(effects
				(font
					(size 1.27 1.27)
				)
			)
		)
		(property "Value" "10KR2F-2-GP"
			(at 0.064008 -3.993896 180)
			(unlocked yes)
			(layer "F.Fab")
			(hide yes)
			(effects
				(font
					(size 1.016 1.016)
					(thickness 0.1524)
				)
			)
		)
		(property "Device Type" "R402H16"
			(at 0.064008 -5.517896 180)
			(unlocked yes)
			(layer "F.Fab")
			(hide yes)
			(effects
				(font
					(size 1.016 1.016)
					(thickness 0.1524)
				)
			)
		)
		(duplicate_pad_numbers_are_jumpers no)
		(fp_line
			(start 0.508 -0.9398)
			(end -0.508 -0.9398)
			(stroke
				(width 0.1524)
				(type default)
			)
			(layer "F.SilkS")
		)
		(fp_line
			(start -0.508 -0.9398)
			(end -0.508 0.9398)
			(stroke
				(width 0.1524)
				(type default)
			)
			(layer "F.SilkS")
		)
		(fp_rect
			(start -0.508 0.9398)
			(end 0.508 -0.9398)
			(stroke
				(width 0)
				(type default)
			)
			(fill no)
			(layer "F.CrtYd")
		)
		(fp_rect
			(start -0.508 0.9398)
			(end 0.508 -0.9398)
			(stroke
				(width 0)
				(type default)
			)
			(fill no)
			(layer "F.Fab")
		)
		(pad "1" smd custom
			(at 0 -0.4445 180)
			(size 0.1397 0.1397)
			(layers "F.Cu" "F.Mask" "F.Paste")
			(net "P1V8")
			(options
				(clearance outline)
				(anchor circle)
			)
			(primitives
				(gr_poly
					(pts
						(arc
							(start -0.1778 -0.2794)
							(mid -0.249642 -0.249642)
							(end -0.2794 -0.1778)
						)
						(arc
							(start -0.2794 0.1778)
							(mid -0.249642 0.249642)
							(end -0.1778 0.2794)
						)
						(arc
							(start 0.1778 0.2794)
							(mid 0.249642 0.249642)
							(end 0.2794 0.1778)
						)
						(arc
							(start 0.2794 -0.1778)
							(mid 0.249642 -0.249642)
							(end 0.1778 -0.2794)
						)
					)
					(width 0)
					(fill yes)
				)
			)
		)
		(pad "2" smd custom
			(at 0 0.4445 180)
			(size 0.1397 0.1397)
			(layers "F.Cu" "F.Mask" "F.Paste")
			(net "PWRGD_P0V975")
			(options
				(clearance outline)
				(anchor circle)
			)
			(primitives
				(gr_poly
					(pts
						(arc
							(start -0.1778 -0.2794)
							(mid -0.249642 -0.249642)
							(end -0.2794 -0.1778)
						)
						(arc
							(start -0.2794 0.1778)
							(mid -0.249642 0.249642)
							(end -0.1778 0.2794)
						)
						(arc
							(start 0.1778 0.2794)
							(mid 0.249642 0.249642)
							(end 0.2794 0.1778)
						)
						(arc
							(start 0.2794 -0.1778)
							(mid 0.249642 -0.249642)
							(end 0.1778 -0.2794)
						)
					)
					(width 0)
					(fill yes)
				)
			)
		)
	)
	(footprint ""
		(layer "F.Cu")
		(at 68.5038 -116.3828 -90)
		(property "Reference" "R268"
			(at 0 0 270)
			(layer "F.SilkS")
			(hide yes)
			(effects
				(font
					(size 1.27 1.27)
				)
			)
		)
		(property "Value" "2K2R2J-2-GP"
			(at 0.064008 -3.993896 270)
			(unlocked yes)
			(layer "F.Fab")
			(hide yes)
			(effects
				(font
					(size 1.016 1.016)
					(thickness 0.1524)
				)
			)
		)
		(property "Device Type" "R402H16"
			(at 0.064008 -5.517896 270)
			(unlocked yes)
			(layer "F.Fab")
			(hide yes)
			(effects
				(font
					(size 1.016 1.016)
					(thickness 0.1524)
				)
			)
		)
		(duplicate_pad_numbers_are_jumpers no)
		(fp_line
			(start -0.508 -0.9398)
			(end -0.508 0.9398)
			(stroke
				(width 0.1524)
				(type default)
			)
			(layer "F.SilkS")
		)
		(fp_line
			(start 0.508 -0.9398)
			(end -0.508 -0.9398)
			(stroke
				(width 0.1524)
				(type default)
			)
			(layer "F.SilkS")
		)
		(fp_rect
			(start -0.508 0.9398)
			(end 0.508 -0.9398)
			(stroke
				(width 0)
				(type default)
			)
			(fill no)
			(layer "F.CrtYd")
		)
		(fp_rect
			(start -0.508 0.9398)
			(end 0.508 -0.9398)
			(stroke
				(width 0)
				(type default)
			)
			(fill no)
			(layer "F.Fab")
		)
		(pad "1" smd custom
			(at 0 -0.4445 270)
			(size 0.1397 0.1397)
			(layers "F.Cu" "F.Mask" "F.Paste")
			(net "P3V3_STBY")
			(options
				(clearance outline)
				(anchor circle)
			)
			(primitives
				(gr_poly
					(pts
						(arc
							(start -0.1778 -0.2794)
							(mid -0.249642 -0.249642)
							(end -0.2794 -0.1778)
						)
						(arc
							(start -0.2794 0.1778)
							(mid -0.249642 0.249642)
							(end -0.1778 0.2794)
						)
						(arc
							(start 0.1778 0.2794)
							(mid 0.249642 0.249642)
							(end 0.2794 0.1778)
						)
						(arc
							(start 0.2794 -0.1778)
							(mid 0.249642 -0.249642)
							(end 0.1778 -0.2794)
						)
					)
					(width 0)
					(fill yes)
				)
			)
		)
		(pad "2" smd custom
			(at 0 0.4445 270)
			(size 0.1397 0.1397)
			(layers "F.Cu" "F.Mask" "F.Paste")
			(net "PU_IBMC_BT_HOLD_N")
			(options
				(clearance outline)
				(anchor circle)
			)
			(primitives
				(gr_poly
					(pts
						(arc
							(start -0.1778 -0.2794)
							(mid -0.249642 -0.249642)
							(end -0.2794 -0.1778)
						)
						(arc
							(start -0.2794 0.1778)
							(mid -0.249642 0.249642)
							(end -0.1778 0.2794)
						)
						(arc
							(start 0.1778 0.2794)
							(mid 0.249642 0.249642)
							(end 0.2794 0.1778)
						)
						(arc
							(start 0.2794 -0.1778)
							(mid 0.249642 -0.249642)
							(end 0.1778 -0.2794)
						)
					)
					(width 0)
					(fill yes)
				)
			)
		)
	)
	(footprint ""
		(layer "F.Cu")
		(at 145.999962 -6.199886)
		(property "Reference" "LED3"
			(at 0 0 0)
			(layer "F.SilkS")
			(hide yes)
			(effects
				(font
					(size 1.27 1.27)
				)
			)
		)
		(property "Value" "LED-BY-14-GP"
			(at -4.7752 -2.1844 0)
			(unlocked yes)
			(layer "F.Fab")
			(hide yes)
			(effects
				(font
					(size 1.016 1.016)
					(thickness 0.1524)
				)
			)
		)
		(property "Device Type" "LED-100-3PH206"
			(at -4.7752 -3.7084 0)
			(unlocked yes)
			(layer "F.Fab")
			(hide yes)
			(effects
				(font
					(size 1.016 1.016)
					(thickness 0.1524)
				)
			)
		)
		(duplicate_pad_numbers_are_jumpers no)
		(fp_line
			(start -3.7592 -1.524)
			(end 3.7592 -1.524)
			(stroke
				(width 0.1524)
				(type default)
			)
			(layer "F.SilkS")
		)
		(fp_line
			(start -3.7592 8.0264)
			(end -3.7592 -1.524)
			(stroke
				(width 0.1524)
				(type default)
			)
			(layer "F.SilkS")
		)
		(fp_line
			(start -1.75387 1.04394)
			(end -1.75387 3.63474)
			(stroke
				(width 0.1524)
				(type default)
			)
			(layer "F.SilkS")
		)
		(fp_line
			(start -1.75387 2.33934)
			(end -3.45567 2.33934)
			(stroke
				(width 0.1524)
				(type default)
			)
			(layer "F.SilkS")
		)
		(fp_line
			(start -1.75387 3.63474)
			(end -0.45847 2.33934)
			(stroke
				(width 0.1524)
				(type default)
			)
			(layer "F.SilkS")
		)
		(fp_line
			(start -0.45847 2.33934)
			(end -1.75387 1.04394)
			(stroke
				(width 0.1524)
				(type default)
			)
			(layer "F.SilkS")
		)
		(fp_line
			(start -0.45847 2.33934)
			(end 0.58293 2.33934)
			(stroke
				(width 0.1524)
				(type default)
			)
			(layer "F.SilkS")
		)
		(fp_line
			(start -0.45847 3.05054)
			(end -0.45847 1.42494)
			(stroke
				(width 0.1524)
				(type default)
			)
			(layer "F.SilkS")
		)
		(fp_line
			(start 0.58293 2.33934)
			(end 1.87833 1.04394)
			(stroke
				(width 0.1524)
				(type default)
			)
			(layer "F.SilkS")
		)
		(fp_line
			(start 0.58293 3.05054)
			(end 0.58293 1.42494)
			(stroke
				(width 0.1524)
				(type default)
			)
			(layer "F.SilkS")
		)
		(fp_line
			(start 1.87833 1.04394)
			(end 1.87833 3.63474)
			(stroke
				(width 0.1524)
				(type default)
			)
			(layer "F.SilkS")
		)
		(fp_line
			(start 1.87833 2.33934)
			(end 2.81813 2.33934)
			(stroke
				(width 0.1524)
				(type default)
			)
			(layer "F.SilkS")
		)
		(fp_line
			(start 1.87833 3.63474)
			(end 0.58293 2.33934)
			(stroke
				(width 0.1524)
				(type default)
			)
			(layer "F.SilkS")
		)
		(fp_line
			(start 3.7592 -1.524)
			(end 3.7592 8.0264)
			(stroke
				(width 0.1524)
				(type default)
			)
			(layer "F.SilkS")
		)
		(fp_line
			(start 3.7592 8.0264)
			(end -3.7592 8.0264)
			(stroke
				(width 0.1524)
				(type default)
			)
			(layer "F.SilkS")
		)
		(fp_circle
			(center -2.54 0)
			(end -1.5494 0)
			(stroke
				(width 0.3048)
				(type default)
			)
			(fill no)
			(layer "F.SilkS")
		)
		(fp_circle
			(center 0 0)
			(end 0.9906 0)
			(stroke
				(width 0.3048)
				(type default)
			)
			(fill no)
			(layer "F.SilkS")
		)
		(fp_circle
			(center 2.54 0)
			(end 3.5306 0)
			(stroke
				(width 0.3048)
				(type default)
			)
			(fill no)
			(layer "F.SilkS")
		)
		(fp_rect
			(start -3.5052 7.7724)
			(end 3.5052 -1.27)
			(stroke
				(width 0)
				(type default)
			)
			(fill no)
			(layer "F.CrtYd")
		)
		(fp_poly
			(pts
				(xy -4.0132 8.2804) (xy -4.0132 -1.778) (xy -3.5052 -1.778) (xy -3.5052 7.7724) (xy 3.5052 7.7724)
				(xy 3.5052 -1.27) (xy -3.50012 -1.27) (xy -3.50012 -1.778) (xy 4.0132 -1.778) (xy 4.0132 8.2804)
			)
			(stroke
				(width 0)
				(type default)
			)
			(fill no)
			(layer "F.CrtYd")
		)
		(fp_rect
			(start -4.0132 8.2804)
			(end 4.0132 -1.778)
			(stroke
				(width 0)
				(type default)
			)
			(fill no)
			(layer "F.Fab")
		)
		(pad "1" thru_hole circle
			(at -2.54 0)
			(size 1.27 1.27)
			(drill 0.889)
			(layers "*.Cu" "*.Mask")
			(remove_unused_layers no)
			(net "EXT2_LED_BLUE")
			(clearance 0.1651)
			(thermal_gap 0.1651)
		)
		(pad "2" thru_hole circle
			(at 0 0)
			(size 1.27 1.27)
			(drill 0.889)
			(layers "*.Cu" "*.Mask")
			(remove_unused_layers no)
			(net "GND")
			(clearance 0.1651)
			(thermal_gap 0.1651)
		)
		(pad "3" thru_hole circle
			(at 2.54 0)
			(size 1.27 1.27)
			(drill 0.889)
			(layers "*.Cu" "*.Mask")
			(remove_unused_layers no)
			(net "EXT2_LED_YELLOW")
			(clearance 0.1651)
			(thermal_gap 0.1651)
		)
	)
	(footprint ""
		(layer "F.Cu")
		(at 46.11116 -163.6903)
		(property "Reference" "TP191"
			(at 0 0 0)
			(layer "F.SilkS")
			(hide yes)
			(effects
				(font
					(size 1.27 1.27)
				)
			)
		)
		(property "Value" "TPAD28-2-GP"
			(at -0.0127 -1.6637 0)
			(unlocked yes)
			(layer "F.Fab")
			(hide yes)
			(effects
				(font
					(size 1.016 1.016)
					(thickness 0.1524)
				)
			)
		)
		(property "Device Type" "TPAD28"
			(at -0.0127 -3.1877 0)
			(unlocked yes)
			(layer "F.Fab")
			(hide yes)
			(effects
				(font
					(size 1.016 1.016)
					(thickness 0.1524)
				)
			)
		)
		(duplicate_pad_numbers_are_jumpers no)
		(fp_poly
			(pts
				(arc
					(start 0.3556 0)
					(mid -0.3556 0)
					(end 0.3556 0)
				)
			)
			(stroke
				(width 0)
				(type default)
			)
			(fill no)
			(layer "F.CrtYd")
		)
		(fp_poly
			(pts
				(arc
					(start 0.6096 0)
					(mid -0.6096 0)
					(end 0.6096 0)
				)
			)
			(stroke
				(width 0)
				(type default)
			)
			(fill no)
			(layer "F.Fab")
		)
		(pad "1" smd circle
			(at 0 0)
			(size 0.7112 0.7112)
			(layers "F.Cu" "F.Mask" "F.Paste")
			(net "TP_BMC_GPIOL5")
		)
	)
	(footprint ""
		(layer "F.Cu")
		(at 76.2508 -150.3426 180)
		(property "Reference" "R307"
			(at 0 0 180)
			(layer "F.SilkS")
			(hide yes)
			(effects
				(font
					(size 1.27 1.27)
				)
			)
		)
		(property "Value" "10KR2F-2-GP"
			(at 0.064008 -3.993896 180)
			(unlocked yes)
			(layer "F.Fab")
			(hide yes)
			(effects
				(font
					(size 1.016 1.016)
					(thickness 0.1524)
				)
			)
		)
		(property "Device Type" "R402H16"
			(at 0.064008 -5.517896 180)
			(unlocked yes)
			(layer "F.Fab")
			(hide yes)
			(effects
				(font
					(size 1.016 1.016)
					(thickness 0.1524)
				)
			)
		)
		(duplicate_pad_numbers_are_jumpers no)
		(fp_line
			(start 0.508 -0.9398)
			(end -0.508 -0.9398)
			(stroke
				(width 0.1524)
				(type default)
			)
			(layer "F.SilkS")
		)
		(fp_line
			(start -0.508 -0.9398)
			(end -0.508 0.9398)
			(stroke
				(width 0.1524)
				(type default)
			)
			(layer "F.SilkS")
		)
		(fp_rect
			(start -0.508 0.9398)
			(end 0.508 -0.9398)
			(stroke
				(width 0)
				(type default)
			)
			(fill no)
			(layer "F.CrtYd")
		)
		(fp_rect
			(start -0.508 0.9398)
			(end 0.508 -0.9398)
			(stroke
				(width 0)
				(type default)
			)
			(fill no)
			(layer "F.Fab")
		)
		(pad "1" smd custom
			(at 0 -0.4445 180)
			(size 0.1397 0.1397)
			(layers "F.Cu" "F.Mask" "F.Paste")
			(net "P3V3_STBY")
			(options
				(clearance outline)
				(anchor circle)
			)
			(primitives
				(gr_poly
					(pts
						(arc
							(start -0.1778 -0.2794)
							(mid -0.249642 -0.249642)
							(end -0.2794 -0.1778)
						)
						(arc
							(start -0.2794 0.1778)
							(mid -0.249642 0.249642)
							(end -0.1778 0.2794)
						)
						(arc
							(start 0.1778 0.2794)
							(mid 0.249642 0.249642)
							(end 0.2794 0.1778)
						)
						(arc
							(start 0.2794 -0.1778)
							(mid 0.249642 -0.249642)
							(end 0.1778 -0.2794)
						)
					)
					(width 0)
					(fill yes)
				)
			)
		)
		(pad "2" smd custom
			(at 0 0.4445 180)
			(size 0.1397 0.1397)
			(layers "F.Cu" "F.Mask" "F.Paste")
			(net "50M_CLK_OE")
			(options
				(clearance outline)
				(anchor circle)
			)
			(primitives
				(gr_poly
					(pts
						(arc
							(start -0.1778 -0.2794)
							(mid -0.249642 -0.249642)
							(end -0.2794 -0.1778)
						)
						(arc
							(start -0.2794 0.1778)
							(mid -0.249642 0.249642)
							(end -0.1778 0.2794)
						)
						(arc
							(start 0.1778 0.2794)
							(mid 0.249642 0.249642)
							(end 0.2794 0.1778)
						)
						(arc
							(start 0.2794 -0.1778)
							(mid 0.249642 -0.249642)
							(end 0.1778 -0.2794)
						)
					)
					(width 0)
					(fill yes)
				)
			)
		)
	)
	(footprint ""
		(layer "F.Cu")
		(at 201.4728 -49.9618)
		(property "Reference" "TP140"
			(at 0 0 0)
			(layer "F.SilkS")
			(hide yes)
			(effects
				(font
					(size 1.27 1.27)
				)
			)
		)
		(property "Value" "TPAD28-2-GP"
			(at -0.0127 -1.6637 0)
			(unlocked yes)
			(layer "F.Fab")
			(hide yes)
			(effects
				(font
					(size 1.016 1.016)
					(thickness 0.1524)
				)
			)
		)
		(property "Device Type" "TPAD28"
			(at -0.0127 -3.1877 0)
			(unlocked yes)
			(layer "F.Fab")
			(hide yes)
			(effects
				(font
					(size 1.016 1.016)
					(thickness 0.1524)
				)
			)
		)
		(duplicate_pad_numbers_are_jumpers no)
		(fp_poly
			(pts
				(arc
					(start 0.3556 0)
					(mid -0.3556 0)
					(end 0.3556 0)
				)
			)
			(stroke
				(width 0)
				(type default)
			)
			(fill no)
			(layer "F.CrtYd")
		)
		(fp_poly
			(pts
				(arc
					(start 0.6096 0)
					(mid -0.6096 0)
					(end 0.6096 0)
				)
			)
			(stroke
				(width 0)
				(type default)
			)
			(fill no)
			(layer "F.Fab")
		)
		(pad "1" smd circle
			(at 0 0)
			(size 0.7112 0.7112)
			(layers "F.Cu" "F.Mask" "F.Paste")
			(net "ICE1_TCK")
		)
	)
	(footprint ""
		(layer "F.Cu")
		(at 157.8864 -38.5064)
		(property "Reference" "TP184"
			(at 0 0 0)
			(layer "F.SilkS")
			(hide yes)
			(effects
				(font
					(size 1.27 1.27)
				)
			)
		)
		(property "Value" "TPAD28-2-GP"
			(at -0.0127 -1.6637 0)
			(unlocked yes)
			(layer "F.Fab")
			(hide yes)
			(effects
				(font
					(size 1.016 1.016)
					(thickness 0.1524)
				)
			)
		)
		(property "Device Type" "TPAD28"
			(at -0.0127 -3.1877 0)
			(unlocked yes)
			(layer "F.Fab")
			(hide yes)
			(effects
				(font
					(size 1.016 1.016)
					(thickness 0.1524)
				)
			)
		)
		(duplicate_pad_numbers_are_jumpers no)
		(fp_poly
			(pts
				(arc
					(start 0.3556 0)
					(mid -0.3556 0)
					(end 0.3556 0)
				)
			)
			(stroke
				(width 0)
				(type default)
			)
			(fill no)
			(layer "F.CrtYd")
		)
		(fp_poly
			(pts
				(arc
					(start 0.6096 0)
					(mid -0.6096 0)
					(end 0.6096 0)
				)
			)
			(stroke
				(width 0)
				(type default)
			)
			(fill no)
			(layer "F.Fab")
		)
		(pad "1" smd circle
			(at 0 0)
			(size 0.7112 0.7112)
			(layers "F.Cu" "F.Mask" "F.Paste")
			(net "ZDEF_EXTB_TP_D2")
		)
	)
	(footprint ""
		(layer "F.Cu")
		(at 45.44568 -123.794012)
		(property "Reference" "R781"
			(at 0 0 0)
			(layer "F.SilkS")
			(hide yes)
			(effects
				(font
					(size 1.27 1.27)
				)
			)
		)
		(property "Value" "0R2J-2-GP"
			(at 0.064008 -3.993896 0)
			(unlocked yes)
			(layer "F.Fab")
			(hide yes)
			(effects
				(font
					(size 1.016 1.016)
					(thickness 0.1524)
				)
			)
		)
		(property "Device Type" "R402H16"
			(at 0.064008 -5.517896 0)
			(unlocked yes)
			(layer "F.Fab")
			(hide yes)
			(effects
				(font
					(size 1.016 1.016)
					(thickness 0.1524)
				)
			)
		)
		(duplicate_pad_numbers_are_jumpers no)
		(fp_line
			(start -0.508 -0.9398)
			(end -0.508 0.9398)
			(stroke
				(width 0.1524)
				(type default)
			)
			(layer "F.SilkS")
		)
		(fp_line
			(start 0.508 -0.9398)
			(end -0.508 -0.9398)
			(stroke
				(width 0.1524)
				(type default)
			)
			(layer "F.SilkS")
		)
		(fp_rect
			(start -0.508 0.9398)
			(end 0.508 -0.9398)
			(stroke
				(width 0)
				(type default)
			)
			(fill no)
			(layer "F.CrtYd")
		)
		(fp_rect
			(start -0.508 0.9398)
			(end 0.508 -0.9398)
			(stroke
				(width 0)
				(type default)
			)
			(fill no)
			(layer "F.Fab")
		)
		(pad "1" smd custom
			(at 0 -0.4445)
			(size 0.1397 0.1397)
			(layers "F.Cu" "F.Mask" "F.Paste")
			(net "FLA_CS_0_R")
			(options
				(clearance outline)
				(anchor circle)
			)
			(primitives
				(gr_poly
					(pts
						(arc
							(start -0.1778 -0.2794)
							(mid -0.249642 -0.249642)
							(end -0.2794 -0.1778)
						)
						(arc
							(start -0.2794 0.1778)
							(mid -0.249642 0.249642)
							(end -0.1778 0.2794)
						)
						(arc
							(start 0.1778 0.2794)
							(mid 0.249642 0.249642)
							(end 0.2794 0.1778)
						)
						(arc
							(start 0.2794 -0.1778)
							(mid 0.249642 -0.249642)
							(end 0.1778 -0.2794)
						)
					)
					(width 0)
					(fill yes)
				)
			)
		)
		(pad "2" smd custom
			(at 0 0.4445)
			(size 0.1397 0.1397)
			(layers "F.Cu" "F.Mask" "F.Paste")
			(net "BMC_CPU_DIS")
			(options
				(clearance outline)
				(anchor circle)
			)
			(primitives
				(gr_poly
					(pts
						(arc
							(start -0.1778 -0.2794)
							(mid -0.249642 -0.249642)
							(end -0.2794 -0.1778)
						)
						(arc
							(start -0.2794 0.1778)
							(mid -0.249642 0.249642)
							(end -0.1778 0.2794)
						)
						(arc
							(start 0.1778 0.2794)
							(mid 0.249642 0.249642)
							(end 0.2794 0.1778)
						)
						(arc
							(start 0.2794 -0.1778)
							(mid 0.249642 -0.249642)
							(end 0.1778 -0.2794)
						)
					)
					(width 0)
					(fill yes)
				)
			)
		)
	)
)
